# Bryce Canyon_Front_Drive_Plane_Board_Stackup.xlsx — Storage_PCB_Test_Note (pcb-stackup)
| 編號(Number) | 內容(Item) | 附加檔案(Files) | 附加說明(Description) |
| 1 | Impedance traceability and test |  | 1、板廠在HVM量產階段採用AQL 0.65 正常檢驗水準二級來抽樣，利用Excel範本(PCB_Vendor_PCB_Number(XXXXX-SA)_Impedance_Report_Template_Date.xlsx)在量產階段(HVM 90天後)，不同lot 的量測結果分開於不同的分頁中，記錄其Min, Max, Mean, Median, Sigma, CP, CK, CPK等數值。 2、阻抗CPK的允收條件為 c= 0 (HVM 90天後)；阻抗數值的允收條件為 ±10%(EVT, DVT, PVT,HVM)。 3、阻抗測試條需擺放於折斷邊上。 |
| 2 | Delta-L coupon test |  | 1、板廠在HVM量產階段每個lot隨機挑選5 pcs且最大總數量為 30 pcs，利用Excel範本(PCB_Vendor_PCB_Number(XXXXX-SA)_Delta-L_Report_Template_Date.xlsx)中的格式及步驟. 2、Delta-L測試條的設計為85 ohm走線，需涵蓋的層面為85 ohm與100 ohm的所有走線層面。 3、損耗的允收條件為為 c= 0 (HVM 90天後)；小於疊構中敘述的dB/inch數值(EVT, DVT, PVT, HVM)。 |
